# TimeCardV9_BOM_8-28-2023.xlsx — TimeCardV9_BOM_8-28-2023 (bom)
| Line # | DNP | Name | Description | Designator | Revision ID | Revision State | Revision Status | Quantity | Manufacturer 1 | Manufacturer Part Number 1 | Manufacturer Lifecycle 1 | Supplier 1 | Supplier Part Number 1 | Supplier Unit Price 1 | Supplier Subtotal 1 |
|  |  | 39-30-0040 | CONN HEADER R/A 4POS 4.2MM | J38 | CMP-2000-05600-2 | New From Design | Up to date | 1 | Molex | 39-30-0040 | Volume Production | Newark | 26AC7279 | 0.90600000000000003 | 0.90600000000000003 |
|  |  | 219-2LPST | Surface Mount DIP Switch Auto Placeable, -55 to 85 degC, 4-Pin SMD, RoHS, Tube | SW2 | CMP-2000-05532-1 | Released | Up to date | 1 | CTS | 219-2LPST | Volume Production | Future Electronics | 2400042 | 0.39500000000000002 | 0.39500000000000002 |
|  |  | 0332-0-43-80-18-27-10-0 | Solder socket for pin headers | SKT1, SKT2, SKT3, SKT4, SKT5, SKT6, SKT7, SKT8, SKT9, SKT10 |  | Not managed |  | 10 |  |  |  |  |  |  |  |
|  |  | 901-143-6RFX | Coaxial connector, 50 Ohm, -65 to 165 degC, 5-Pin THD, RoHS, Bulk | AN1, AN2, AN3, AN4 | CMP-2000-05705-1 | Released | Up to date | 4 | Adam Equipment | RF2-49B-T-00-50-G-HDW | Unknown | Arrow Electronics | RF2-49B-T-00-50-G-HDW | 2.5 | 9.99 |
|  |  | 04023C104KAT2A | General Purpose Ceramic Capacitor, 0402, 100nF, 10%, X7R, 15%, 25V | C18, C26, C27, C28, C29, C33, C69, C70, C74, C83, C89, C92, C93, C94, C95, C96, C97, C98, C99, C100, C101, C102, C103, C104, C105, C106, C107, C108, C109, C110, C112, C113, C115 | CMP-2008-02519-2 | Released | Up to date | 33 | Kyocera AVX | 04023C104KAT2A | Volume Production | Newark | 95W1317 | 7.0000000000000001E-3 | 0.23100000000000001 |
|  |  | 04023D104KAT2A |  | C19, C21, C66, C67, C84 | CMP-1034-02072-2 | Released | Up to date | 5 | Kyocera AVX | 04023C104KAT2A | Volume Production | Newark | 95W1317 | 7.0000000000000001E-3 | 3.5000000000000003E-2 |
|  |  | 47589-0001 | Right Angle Female Type AB Micro USB Connector, 30 V, 1.8 A, -30 to 85 degC, RoHS, Tape and Reel | J43 | CMP-2000-05610-1 | Released | Up to date | 1 | Molex | 47589-0001 | Volume Production | Newark | 40P3749 | 0.32300000000000001 | 0.32300000000000001 |
|  |  | 155124M173200 | LED (Multiple) | D13, D14, D15, D16, D17, D18 |  | Not managed |  | 6 | Wurth Electronics | 155124M173200 | Unknown | Digi-Key | 732-11414-1-ND | 0.53 | 3.18 |
|  |  | 1571983-4 | SWITCH SLIDE DIP SPST 25MA 24V | SW1 | CMP-03400-000014-1 | New From Design | Up to date | 1 | TE Connectivity | 1571983-4 | Volume Production | Future Electronics | 9787847 | 1.1499999999999999 | 1.1499999999999999 |
|  |  | 1909763-1 | Ultra Miniature Coaxial Connector Jack, 60 V, 50 Ohm, -40 to 90 degC, RoHS, Tape and Reel | J1, J2, J3, J4 | CMP-2000-07505-1 | Released | Out of date | 4 | TE Connectivity AMP | 1909763-1 | Volume Production | Newark | 24AC1644 | 0.25600000000000001 | 1.02 |
|  |  | 2199119-3 | CONN M.2 FEMALE 67POS 0.020 GOLD | J44, J45 | CMP-03365-000004-1 | New From Design | Up to date | 2 | TE Connectivity | 2199119-3 | Volume Production | Newark | 28AC8045 | 1.03 | 2.06 |
|  |  | 8240136 | TVS Diode WE-TVS-HS, VRWM=3.3V | D1, D2 | CMP-1486-00002-1 | Released | Out of date | 2 | Wurth Electronics | 8240136 | Volume Production | Digi-Key | 732-4472-1-ND | 1.28 | 2.56 |
|  |  | 61300411121 | THT Vertical Pin Header WR-PHD, Pitch 2.54 mm, Single Row, 4 pins | P5 | CMP-1502-01064-1 | Released | Out of date | 1 | Wurth Electronics | 61300411121 | Volume Production | Digi-Key | 732-5317-ND | 0.19 | 0.19 |
|  |  | ABS07-32.768KHZ-T | Crystal 32.768kHz ±20ppm (Tol) 12.5pF FUND 70kΩ 2-Pin CSMD T/R | Y1 | CMP-0447-00001-4 | Released | Up to date | 1 | Abracon | ABS07-32.768KHZ-T | Volume Production | Mouser | 815-ABS07-32.768KHZT | 0.62 | 0.62 |
|  |  | AT24MAC402-STUM-T | IC EEPROM 2K I2C 1MHZ SOT23-5 | U7 | CMP-06313-000011-1 | New From Design | Up to date | 1 | Microchip | AT24MAC402-STUM-T | Volume Production |  |  |  |  |
|  |  | BAT54SW | DIO, SCHOTTKY, BAT54S, DUAL SERIES, 30V, 200MA, SC-70 | D5, D6, D7, D8 |  | Not managed |  | 4 | Diodes | BAT54SWQ-7-F | Volume Production | Digi-Key | BAT54SWQ-7-FDICT-ND | 0.33 | 1.32 |
|  |  | BLM18KG601SN1D | Chip Ferrite Bead, 0603, 600Ω @ 100MHz, 0.15Ω, 25%, 1.3A | FB1 | CMP-0686-00581-3 | Released | Up to date | 1 | Murata | BLM18KG601SN1D | Volume Production | Arrow Electronics | BLM18KG601SN1D | 8.09E-2 | 8.09E-2 |
|  |  | BME280 | SENSOR PRESSURE HUMIDITY TEMP | U14 | CMP-2000-05073-3 | New From Design | Up to date | 1 | Bosch | BME280 | Volume Production | Future Electronics | 2053946 | 4.57 | 4.57 |
|  |  | BNO055 | IMU ACCEL/GYRO/MAG I2C 28LGA | U13 | CMP-2000-05075-4 | New From Design | Up to date | 1 | Bosch | BNO055 | Volume Production |  |  |  |  |
|  |  | C0603C105K3PACTU | CAP CER 1UF 25V X5R 0603 | C38 | CMP-2006-02216-3 | Released | Up to date | 1 | KEMET | C0603C105K3PACTU | Volume Production | Newark | 93K5996 | 4.0000000000000001E-3 | 4.0000000000000001E-3 |
|  |  | C0603X104K5RACAUTO |  | C2, C23, C24, C25, C30, C31, C36, C37, C40, C43, C54, C57, C59, C61, C63, C64 | CMP-2006-00003-1 | Released | Out of date | 16 | KEMET | C0603X104K5RACAUTO | Volume Production | Newark | 91Y8329 | 3.7999999999999999E-2 | 0.60799999999999998 |
|  |  | C1005X5R1C225K050BC | Multilayer Ceramic Capacitors 2.2μF ±10% 16V X5R SMD 0402 | C3, C5, C7, C9, C16, C81 | CMP-2000-05998-2 | Released | Up to date | 6 | TDK | C1005X5R1C225K050BC | Volume Production | Mouser | 810-C1005X5R1C225K | 0.11899999999999999 | 1.19 |
|  |  | C3216X5R1C476M160AB | Multilayer Ceramic Capacitors 47uF ±20% 16V X5R SMD 1206 | C13, C78 | CMP-2000-07442-2 | Released | Up to date | 2 | TDK | C3216X5R1C476M160AB | Volume Production | Newark | 12T1951 | 0.11 | 0.22 |
|  |  | CAP_0402_0.1UF_50V | CAP, CER, 0.1UF, 50V, 10%, X7R, AEC-Q200, 0402 | C44, C45, C46, C47, C48, C49, C50, C51, C52, C53 |  | Not managed |  | 10 |  |  |  | Digi-Key | 445-6899-1-ND |  |  |
|  |  | CAP_0805_10UF_25V | CAP, CER, 10.UF, 25V, 10%, X5R, 0805 | C1, C62 |  | Not managed |  | 2 | Taiyo | TMK212BBJ106KG-T | Unknown | MOUSER | 963-TMK212BBJ106KG-T |  |  |
|  |  | CC0402JRNPO9BN220 | Chip Capacitor, 22 pF, +/- 5%, 50 V, -55 to 125 degC, 0402 (1005 Metric), RoHS, Tape and Reel | C39, C68 | CMP-2100-03590-1 | Released | Up to date | 2 | Yageo | CC0402JRNPO9BN220 | Volume Production | Newark | 69C9585 | 1.0999999999999999E-2 | 0.11 |
|  |  | CC0402KRX7R9BB103 | CAP CER 10000PF 50V X7R 0402 | C86, C91 | CMP-2100-03592-2 | New From Design | Up to date | 2 | Yageo | CC0402KRX7R9BB103 | Volume Production | Newark | 69AH7183 | 3.0000000000000001E-3 | 6.0000000000000001E-3 |
|  |  | CL05A475MO5NUNC | Cap Ceramic 4.7uF 16V X5R ±20% SMD 0402 +85°C Paper T/R | C90 | CMP-13271-001468-1 | New From Design | Up to date | 1 | Samsung | CL05A475MO5NUNC | Volume Production | Mouser | 187-CL05A475MO5NUNC | 0.41 | 0.41 |
|  |  | CR0402-FX-1002GLF |  | R59, R60, R184, R185 | CMP-2002-04694-1 | Released | Up to date | 4 | Bourns | CR0402-FX-1002GLF | Volume Production | Arrow Electronics | CR0402-FX-1002GLF | 4.4000000000000003E-3 | 4.3999999999999997E-2 |
|  |  | CR0402-FX-4701GLF |  | R5, R14, R15, R16, R17, R29, R30, R31, R32, R70, R113, R114, R115, R116, R117, R118, R119, R120, R123, R124, R132, R133, R134, R135, R136, R137 | CMP-2002-05217-1 | Released | Up to date | 26 | Bourns | CR0402-FX-4701GLF | Volume Production | Newark | 34AK1324 | 1E-3 | 2.5999999999999999E-2 |
|  |  | CRCW040227R0FKED |  | R13, R42, R43, R76, R81, R84, R85, R86, R87, R90, R91, R92, R93, R94, R95, R111, R121, R126, R127, R128 | CMP-2002-08434-1 | Released | Up to date | 20 | Vishay | CRCW040227R0FKED | Volume Production | Newark | 72M6769 | 5.0000000000000001E-3 | 0.1 |
|  |  | CRCW080533R0FKEA | RES, 33 OHM, 1%, 1/8W, TF, 0805 | R18, R19, R20, R21 |  | Not managed |  | 4 | Vishay | CRCW080533R0FKEA | Volume Production | Digi-Key | 541-33.0CCT-ND | 0.1 | 0.4 |
|  |  | CRCW0402200RFKTD |  | R112, R122, R125, R178, R179 | CMP-2002-08352-1 | Released | Up to date | 5 | Vishay Dale | CRCW0402200RFKTD | Volume Production | Digi-Key | 541-CRCW0402200RFKTDCT-ND | 0.13 | 0.65 |
|  |  | CRCW0603110RFKEA |  | R12 | CMP-2000-03854-1 | Released | Up to date | 1 | Vishay | CRCW0603110RFKEA | Volume Production | Newark | 52K8095 | 5.0000000000000001E-3 | 5.0000000000000001E-3 |
|  |  | CRCW12060000Z0EAHP |  | R45 | CMP-2003-04873-1 | Released | Up to date | 1 | Vishay Dale | CRCW12060000Z0EAHP | Volume Production | Mouser | 71-CRCW12060000Z0EAH | 0.26 | 0.26 |
|  |  | DS90LV027AQMA | Automotive LVDS Dual Differential Driver, 8-pin Narrow SOIC | U3 | CMP-0058-01000-2 | Released | Up to date | 1 | TI National Semiconductor | DS90LV027AQMA | Unknown |  |  |  |  |
|  |  | DS90LV028AQMA | Automotive LVDS Dual Differential Line Receiver, 8-pin Narrow SOIC | U4 | CMP-0058-01010-2 | Released | Up to date | 1 | TI National Semiconductor | DS90LV028AQMA | Volume Production |  |  |  |  |
|  |  | EMK105BJ105KV-F | None | C17, C32, C82, C111, C114 | CMP-14477-000104-2 | New From Design | Up to date | 5 | Taiyo Yuden | EMK105BJ105KV-F | Volume Production | Newark | 84R9109 | 6.0000000000000001E-3 | 0.03 |
|  |  | EMK105BJ105MV-F | None | C65 | CMP-14477-003537-2 | New From Design | Up to date | 1 | Taiyo Yuden | EMK105BJ105MV-F | Volume Production | Newark | 02AH5329 | 6.0000000000000001E-3 | 6.0000000000000001E-3 |
|  |  | EMK107BBJ106MA-T | Multilayer Ceramic Capacitor 10uF 16V X5R 20% SMD 0603 T/R | C6, C8, C15, C20, C22, C80, C85 | CMP-2000-06226-4 | Released | Up to date | 7 | Taiyo Yuden | EMK107BBJ106MA-T | Volume Production | Mouser | 963-EMK107BBJ106MA-T | 0.151 | 1.51 |
|  |  | ERA-2AED122X |  | R26 | CMP-2002-05839-1 | Released | Up to date | 1 | Panasonic | ERA-2AED122X | Volume Production | Arrow Electronics | ERA-2AED122X | 8.8900000000000007E-2 | 8.8900000000000007E-2 |
|  |  | ERA-2AED222X |  | R61 | CMP-2002-05848-1 | Released | Up to date | 1 | Panasonic | ERA-2AED222X | Volume Production | Digi-Key | P2.2KDECT-ND | 0.19 | 0.19 |
|  |  | ERJ2GE0R00X | Chip Resistor, 0 Ohm, 0.1 W, -55 to 155 degC, 0402 (1005 Metric), RoHS, Tape and Reel | R3, R4, R54, R62, R64, R65, R66, R69, R79, R80, R138, R139 | CMP-2000-07451-1 | Released | Up to date | 12 | Panasonic | ERJ-2GE0R00X | Volume Production | Newark | 63W0591 | 5.0000000000000001E-3 | 0.06 |
|  |  | ERJ-2GE0R00X | RES, 0. OHM, 1%, 1/16W, TF, AEC-Q200, 0402 | R23, R24 |  | Not managed |  | 2 | Panasonic | ERJ-2GE0R00X | Volume Production | Digi-Key | P0.0JCT-ND | 0.1 | 0.2 |
|  |  | ERJ-2GEJ103X |  | R49, R180, R181, R182 | CMP-2002-00433-1 | Released | Up to date | 4 | Panasonic | ERJ-2GEJ103X | Volume Production | Newark | 12AC0920 | 4.0000000000000001E-3 | 1.6E-2 |
|  |  | ERJ-2RKF1502X | RES SMD 15K OHM 1% 1/10W 0402 | R83 | CMP-2002-00694-4 | New From Design | Up to date | 1 | Panasonic | ERJ-2RKF1502X | Volume Production | Newark | 64R5259 | 7.0000000000000001E-3 | 7.0000000000000001E-3 |
|  |  | ERJ-2RKF2000X | RES SMD 200 OHM 1% 1/10W 0402 | R1, R77 | CMP-2002-00757-2 | Released | Up to date | 2 | Panasonic | ERJ-2RKF2000X | Volume Production | Newark | 73T6485 | 4.0000000000000001E-3 | 8.0000000000000002E-3 |
|  |  | ERJ-2RKF4701X | Chip Resistor, 4.7 KOhm, +/- 1%, 0.1 W, -55 to 155 degC, 0402 (1005 Metric), RoHS, Tape and Reel | R50, R51, R52, R53, R55, R57, R58, R108, R109 | CMP-2002-01154-4 | Released | Up to date | 9 | Panasonic | ERJ-2RKF4701X | Volume Production | Newark | 85Y8345 | 4.0000000000000001E-3 | 3.5999999999999997E-2 |
|  |  | ERJ-3EKF2000V |  | R35, R36, R38, R39 | CMP-2000-00316-1 | Released | Out of date | 4 | Panasonic | ERJ-3EKF2000V | Volume Production | Newark | 63W0785 | 6.0000000000000001E-3 | 0.06 |
|  |  | ERJ-3EKF4701V | Precision Thick Film Chip Resistor, 4.7 KOhm, +/- 1%, -55 to 155 degC, 0603 (1608 Metric), RoHS, Tape and Reel | R41 | CMP-1012-00586-3 | Released | Up to date | 1 | Yageo | RC0603FR-074K7L | Volume Production | Newark | 75X0151 | 3.0000000000000001E-3 | 3.0000000000000001E-3 |
|  |  | ERJ-3EKF4701V | RES, 4.7K, 1%, 1/10W, TF, 0603 | R22 |  | Not managed |  | 1 | Panasonic | ERJ-3EKF4701V | Volume Production | Digi-Key | P4.70KHCT-ND | 0.1 | 0.1 |
|  | DNP | EXT GPIO | Header, 6-Pin, Dual row | P3 |  | Not managed |  | 1 |  |  |  |  |  |  |  |
|  |  | FT234XD-R | IC USB SERIAL BASIC UART 12DFN | U20 | CMP-0248-00027-3 | New From Design | Up to date | 1 | FTDI | FT234XD-R | Volume Production | Arrow Electronics | FT234XD-R | 2.21 | 2.21 |
|  |  | FUSE_0603_5.00A | FUSE SLOW 5.00A 32V M 0603 | F1 |  | Not managed |  | 1 | Bourns | SF-0603S500-2 | Volume Production | Digi-Key | SF-0603S500-2CT-ND | 0.6 | 0.6 |
|  |  | GNSS Header 16-pin |  | J6, J13 |  | Not managed |  | 2 | Samtec | SQW-108-01-F-D-VS | Volume Production | Digi-Key | SAM11878-ND | 3.61 | 7.22 |
|  |  | GNSS Standoff |  | J5, J7, J8, J9, J10, J11, J12, J14 |  | Not managed |  | 8 | Keystone Electronics | 24393 | Volume Production | Digi-Key | 36-24393-ND | 0.72 | 5.76 |
|  |  | GRM31CR71H475KA12L | Chip Multilayer Ceramic Capacitors for General Purpose, 1206, 4.7uF, X7R, 15%, 10%, 50V | C11, C12, C76, C77 | CMP-1037-04923-3 | New From Design | Up to date | 4 | Murata | GRM31CR71H475KA12L | Volume Production | Newark | 08AC2721 | 0.10199999999999999 | 0.40799999999999997 |
|  |  | GRM1555C1H470JA01D |  | C87, C88 | CMP-2008-04368-1 | Released | Up to date | 2 | Murata | GRM1555C1H470JA01D | Not Recommended for New Design | Mouser | 81-GRM1555C1H470JA1D | 1.7999999999999999E-2 | 0.18 |
|  |  | INA219BIDR | IC MONITOR PWR/CURR BIDIR 8-SOIC | U2, U17, U19 | CMP-0704-00005-3 | Released | Up to date | 3 | Texas Instruments | INA219BIDR | Volume Production | Arrow Electronics | INA219BIDR | 1.77 | 5.32 |
|  |  | IS32FL3207 |  | U6 |  | Not managed |  | 1 | ISSI | IS32FL3207-QWLA3-TR | Unknown | Digi-Key | 2521-IS32FL3207-QWLA3-TRCT-ND | 2.09 | 2.09 |
|  |  | LTST-C191KGKT | LED GREEN CLEAR SMD | D3, D4, D9, D10, D11, D12, D19, D20, D21, D22, D24 | CMP-2000-05198-2 | New From Design | Up to date | 11 | Vishay Lite-On | LTST-C191KGKT | Volume Production | Mouser | 859-LTST-C191KGKT | 0.14199999999999999 | 1.56 |
|  |  | M3 screw |  | J15, J16, J17, J18, J19, J20, J21, J22, J23, J24, J25, J26, J27, J28, J29, J30, J32, J33 |  | Not managed |  | 18 | APM Hexseal | RM3X6MM2701 | Volume Production | Digi-Key | 335-1156-ND | 0.46 | 8.2799999999999994 |
|  | DNP | MAC-SA5X | MOD, MAC, MAC-SA5X, ATOMIC CLOCK | U10 |  | Not managed |  | 1 |  |  |  |  |  |  |  |
|  |  | MBRD10200CT-13 | No Description Available | CR1 |  | Not managed |  | 1 |  |  |  |  |  |  |  |
|  |  | MC00625W0402120K |  | R6, R9, R129, R183 | CMP-2002-06039-1 | Released | Up to date | 4 | Multicomp | MC00625W0402120K | Volume Production |  |  |  |  |
|  |  | MUN12AD06-SM | No Description Available | U1, U24 |  | Not managed |  | 2 |  |  |  |  |  |  |  |
|  |  | NC7WV125K8X | Integrated Circuit | U8, U11, U12, U16 |  | Not managed |  | 4 | ON Semiconductor / Fairchild | NC7WV125K8X | Volume Production | Farnell | 2824987 | 0.42947999999999997 | 1.72 |
|  |  | NCP176AMX330TCG | IC REG LINEAR 3.3V 500MA 6XDFN | U25, U33 | CMP-07128-000022-1 | New From Design | Up to date | 2 | ON Semiconductor | NCP176AMX330TCG | Volume Production | Farnell | 2507589 | 0.36881000000000003 | 0.73763000000000001 |
|  |  | PCA9546ARGVR | 4-Channel I2C and SMBus Multiplexer with Reset Functions, 2.3 to 5.5 V, -40 to 85 degC, 16-pin VQFN (RGV), Green (RoHS & no Sb/Br) | U27 | CMP-0314-00065-2 | Released | Up to date | 1 | Texas Instruments | PCA9546ARGVR | Volume Production | Arrow Electronics | PCA9546ARGVR | 1.1000000000000001 | 1.1000000000000001 |
|  | DNP | PCIex4 | PCIE x4 Edge Connector,OrCAD Symbol,NC | P2 |  | Not managed |  | 1 |  |  |  |  |  |  |  |
|  |  | PI3A412ZHE | No Description Available | U28, U29 |  | Not managed |  | 2 |  |  |  |  |  |  |  |
|  |  | RC0402FR-0710KL |  | R78, R82, R88, R89, R140, R141, R186 | CMP-2002-07353-1 | Released | Up to date | 7 | Yageo | RC0402FR-0710KL | Volume Production |  |  |  |  |
|  |  | RC0402FR-0749R9L |  | R96, R97, R98, R99, R142, R143, R144, R145, R146, R147, R150, R152, R171, R175, R176, R177 | CMP-2002-07709-1 | Released | Up to date | 16 | Yageo | RC0402FR-0749R9L | Volume Production | Mouser | 603-RC0402FR-0749R9L | 8.9999999999999993E-3 | 0.14399999999999999 |
|  |  | RC0402FR-07147KL |  | R2 | CMP-2002-07394-1 | Released | Up to date | 1 | Yageo | RC0402FR-07147KL | Volume Production | Newark | 68AK6527 | 2E-3 | 2E-3 |
|  |  | RC0603FR-074K7L | Chip Resistor, 4.7 KOhm, +/- 1%, 0.1 W, -55 to 155 degC, 0603 (1608 Metric), RoHS, Tape and Reel | R10, R11 | CMP-2000-06942-1 | Released | Up to date | 2 | Yageo | RC0603FR-074K7L | Volume Production | Newark | 75X0151 | 3.0000000000000001E-3 | 6.0000000000000001E-3 |
|  |  | RC0603FR-0749R9L | General Purpose Chip Resistor, 49.9 Ohm, +/- 1%, -55 to 155 degC, 0603 (1608 Metric), RoHS, Tape and Reel | R25, R28, R33, R34 | CMP-1659-00036-1 | Released | Up to date | 4 | Yageo | RC0603FR-0749R9L | Volume Production | Mouser | 603-RC0603FR-0749R9L | 1.0999999999999999E-2 | 0.11 |
|  | DNP | RCB-F9T | MOD, GPS | U9 |  | Not managed |  | 1 |  |  |  | Digi-Key | 672-RCB-F9T-ND |  |  |
|  | DNP | RCB-F9T-1 | MOD, GPS | U15 |  | Not managed |  | 1 |  |  |  | Digi-Key | 672-RCB-F9T-ND |  |  |
|  |  | RG1005R-220-D-T10 | Automotive Metal Thin Film Chip Resistor, 0402, 22Ω, 0.5%, 100ppm/°C, 0.0625W, 75V | R63 | CMP-2002-01415-2 | Released | Up to date | 1 | Susumu | RG1005R-220-D-T10 | Volume Production | Mouser | 754-RG1005R-220DT10 | 0.14000000000000001 | 0.14000000000000001 |
|  |  | RMCF0603FT10K0 | Chip Resistor, 10 KOhm, +/- 1%, 0.1 W, -55 to 155 degC, 0603 (1608 Metric), RoHS, Tape and Reel | R37 | CMP-2000-06990-1 | Released | Out of date | 1 | Stackpole Electronics | RMCF0603FT10K0 | Volume Production | Digi-Key | RMCF0603FT10K0CT-ND | 0.1 | 0.1 |
|  |  | RT0402DRD072KL |  | R68 | CMP-2002-02670-1 | Released | Up to date | 1 | Yageo | RT0402DRD072KL | Volume Production | Arrow Electronics | RT0402DRD072KL | 0.15790000000000001 | 0.15790000000000001 |
|  |  | RT0402DRE0788K7L | RES SMD 88.7K OHM 0.5% 1/16W | R67 | CMP-2002-03021-2 | New From Design | Up to date | 1 | Yageo | RT0402DRE0788K7L | Volume Production | Digi-Key | 311-2330-1-ND | 0.17 | 0.17 |
|  |  | RT0402DRE07160RL | RES SMD 160 OHM 0.5% 1/16W 0402 | R27 | CMP-03412-035461-1 | New From Design | Up to date | 1 | Yageo | RT0402DRE07160RL | Volume Production |  |  |  |  |
|  |  | SA53 Screw |  | J39, J40, J41, J42 |  | Not managed |  | 4 | B&F Fastener | PMSSS2560025PH | Volume Production | Digi-Key | H700-ND |  |  |
|  |  | SA53_Header |  | J31 |  | Not managed |  | 1 | Molex | 52991-0208 | Volume Production | Digi-Key | WM24007CT-ND | 1.46 | 1.46 |
|  |  | Single FPGA Conn |  | J34, J35, J36, J37 |  | Not managed |  | 4 | Panasonic | AXK680347YG | Volume Production | Digi-Key | 255-3246-1-ND | 2.99 | 11.96 |
|  |  | SMDJ12A | TVS DIODE 12V 19.9V DO214AB | D23 | CMP-08607-000111-1 | New From Design | Up to date | 1 | Littelfuse | SMDJ12A | Not Recommended for New Design | Arrow Electronics | SMDJ12A | 0.54020000000000001 | 0.54020000000000001 |
|  |  | T495D107K016ATE125 | CAP TANT 100UF 10% 16V 2917 | C10, C14, C75, C79 | CMP-2000-07207-2 | Released | Up to date | 4 | KEMET | T495D107K016ATE125 | Volume Production | Newark | 95W0168 | 1.34 | 5.36 |
|  |  | T521X476M035ATE030 | CAP TANT POLY 47UF 35V 2917 | C72, C73 | CMP-03016-000019-1 | New From Design | Up to date | 2 | KEMET | T521X476M035ATE030 | Volume Production | Avnet | 96Y7534 | 3.62 | 7.24 |
|  |  | TAJE477K010RNJ | 470uF 10V  ±10% 500mΩ 2917  SMD Tantalum Capacitor | C4, C71 | CMP-04424-000243-1 | New From Design | Up to date | 2 | Kyocera AVX | TAJE477K010RNJ | Volume Production | Arrow Electronics | TAJE477K010RNJ | 1.29 | 2.57 |
|  |  | TMK212BBJ106KG-T | None | C34, C35, C41, C42, C55, C56, C58, C60 | CMP-14477-000079-2 | New From Design | Out of date | 8 | Taiyo Yuden | TMK212BBJ106KG-T | Volume Production | Newark | 79T3103 | 1.7999999999999999E-2 | 0.14399999999999999 |
|  |  | TMUX1072RUTR | IC SWITCH SPDT DUAL 12UQFN | U21, U22, U23, U26, U30, U31 | CMP-04892-000114-1 | New From Design | Up to date | 6 | Texas Instruments | TMUX1072RUTR | Volume Production | Arrow Electronics | TMUX1072RUTR | 0.8256 | 4.95 |
|  |  | TPS2116DRLR | 1.6-V to 5.5-V, 40-mΩ, 2.5-A, low-IQ, priority power multiplexer 8-SOT-5X3 -40 to 125 | U32, U34 |  | Not managed |  | 2 | Texas Instruments | TPS2116DRLR | Volume Production | LCSC | C3235557 | 0.70960000000000001 | 1.42 |
|  |  | TSM-105-01-L-DV | 0.025" SQ Post Header, Surface Mount, Vertical, -55 to 125 degC, 2.54 mm Pitch, 10-Pin, Male, RoHS | P4 | CMP-1024-00233-1 | Released | Up to date | 1 | Samtec | TSM-105-01-L-DV | Volume Production | Avnet | TSM-105-01-L-DV | 1.69 | 1.69 |
|  |  | TSW-105-05-L-S | 0.025" SQ Post Header, Through-hole, Vertical, -55 to 125 degC, 2.54 mm Pitch, 5-Pin, Male, RoHS | P1 | CMP-1024-00366-1 | Released | Up to date | 1 | Samtec | TSW-105-05-L-S | Volume Production | Newark | 12P1441 | 0.82699999999999996 | 0.82699999999999996 |
|  |  | WSL12062L000FEA18 |  | R7, R8, R72 | CMP-2003-04334-1 | Released | Up to date | 3 | Vishay Dale | WSL12062L000FEA18 | Volume Production | Digi-Key | 541-9996-1-ND | 0.76 | 2.2799999999999998 |
